G04*
G04 #@! TF.GenerationSoftware,Altium Limited,Altium Designer,22.4.2 (48)*
G04*
G04 Layer_Color=8388736*
%FSLAX25Y25*%
%MOIN*%
G70*
G04*
G04 #@! TF.SameCoordinates,446674BB-F454-490D-8607-5140536C8ADF*
G04*
G04*
G04 #@! TF.FilePolarity,Negative*
G04*
G01*
G75*
%ADD37R,0.12362X0.06063*%
%ADD51R,0.03150X0.03150*%
%ADD58R,0.03150X0.03543*%
%ADD60R,0.03543X0.02953*%
%ADD66R,0.03937X0.04921*%
%ADD67R,0.04921X0.03937*%
%ADD76R,0.02657X0.00984*%
%ADD77R,0.00984X0.02657*%
%ADD78R,0.01968X0.01378*%
G04:AMPARAMS|DCode=79|XSize=40.88mil|YSize=20.95mil|CornerRadius=10.48mil|HoleSize=0mil|Usage=FLASHONLY|Rotation=270.000|XOffset=0mil|YOffset=0mil|HoleType=Round|Shape=RoundedRectangle|*
%AMROUNDEDRECTD79*
21,1,0.04088,0.00000,0,0,270.0*
21,1,0.01993,0.02095,0,0,270.0*
1,1,0.02095,0.00000,-0.00996*
1,1,0.02095,0.00000,0.00996*
1,1,0.02095,0.00000,0.00996*
1,1,0.02095,0.00000,-0.00996*
%
%ADD79ROUNDEDRECTD79*%
%ADD80R,0.02095X0.04088*%
%ADD84R,0.31496X0.13583*%
%ADD85R,1.35433X0.23032*%
%ADD86R,0.06509X0.08280*%
%ADD87R,0.07887X0.01784*%
%ADD88R,0.05131X0.04934*%
%ADD89R,0.12217X0.22060*%
%ADD90R,0.03044X0.08556*%
%ADD91R,0.03635X0.04737*%
%ADD92R,0.05328X0.06509*%
%ADD93R,0.06509X0.05328*%
%ADD94R,0.04737X0.03635*%
%ADD95R,0.04147X0.04540*%
%ADD96R,0.04737X0.04540*%
%ADD97R,0.06115X0.07493*%
%ADD98R,0.01784X0.06902*%
%ADD99R,0.07493X0.06115*%
%ADD100R,0.06902X0.01784*%
%ADD101R,0.07450X0.05200*%
%ADD102R,0.05800X0.20800*%
%ADD103R,0.03556X0.04343*%
%ADD104R,0.04540X0.06509*%
%ADD105R,0.06509X0.04540*%
%ADD106R,0.04343X0.02769*%
%ADD107R,0.02769X0.04343*%
%ADD108R,0.04147X0.01981*%
%ADD109R,0.09087X0.05209*%
%ADD110R,0.04540X0.03950*%
%ADD111R,0.04343X0.01824*%
%ADD112R,0.01824X0.04343*%
%ADD113R,0.13595X0.13595*%
%ADD114R,0.04343X0.03162*%
%ADD115R,0.02965X0.03162*%
%ADD116R,0.04540X0.04540*%
%ADD117R,0.09461X0.04934*%
%ADD118R,0.04934X0.04737*%
%ADD119R,0.04540X0.04540*%
%ADD120R,0.04934X0.05131*%
%ADD121R,0.03753X0.04147*%
%ADD122R,0.06312X0.06312*%
%ADD123R,0.04737X0.06312*%
%ADD124R,0.03162X0.03950*%
%ADD125R,0.03162X0.03359*%
%ADD126R,0.03600X0.17300*%
%ADD127R,0.03600X0.13400*%
%ADD128O,0.09461X0.03162*%
%ADD129O,0.08280X0.03162*%
%ADD130R,0.04540X0.04737*%
%ADD131R,0.04737X0.04147*%
%ADD132R,0.04343X0.03556*%
%ADD133C,0.06706*%
%ADD134R,0.06706X0.06706*%
%ADD135C,0.08300*%
%ADD136C,0.05800*%
%ADD137C,0.10642*%
%ADD138C,0.02966*%
%ADD139R,0.00800X0.00800*%
%ADD140C,0.07398*%
%ADD141C,0.09461*%
%ADD142R,0.08674X0.08674*%
%ADD143C,0.00800*%
%ADD144C,0.25800*%
%ADD145C,0.02400*%
%ADD146C,0.02200*%
%ADD147C,0.20800*%
%ADD148C,0.02769*%
G36*
X322835Y-335974D02*
X123031D01*
Y-136171D01*
X322835D01*
Y-335974D01*
D02*
G37*
D37*
X672835Y-214469D02*
D03*
Y-240650D02*
D03*
Y-289862D02*
D03*
Y-263681D02*
D03*
D51*
X40354Y14764D02*
D03*
Y8858D02*
D03*
X33465Y14764D02*
D03*
Y8858D02*
D03*
X26575Y14764D02*
D03*
Y8858D02*
D03*
X47244Y14764D02*
D03*
Y8858D02*
D03*
D58*
X82677Y-116535D02*
D03*
Y-109843D02*
D03*
D60*
X75787Y-127756D02*
D03*
Y-123031D02*
D03*
D66*
X643701Y-58907D02*
D03*
X651575D02*
D03*
X609252Y-21506D02*
D03*
X617126D02*
D03*
D67*
X89567Y-98277D02*
D03*
Y-90403D02*
D03*
X123031Y-79970D02*
D03*
Y-72096D02*
D03*
D76*
X481250Y-121899D02*
D03*
Y-123868D02*
D03*
Y-125836D02*
D03*
Y-127805D02*
D03*
X491191D02*
D03*
Y-125836D02*
D03*
Y-123868D02*
D03*
Y-121899D02*
D03*
D77*
X484252Y-128838D02*
D03*
X486221D02*
D03*
X488189D02*
D03*
Y-120866D02*
D03*
X486221D02*
D03*
X484252D02*
D03*
D78*
X519783Y-126131D02*
D03*
Y-128691D02*
D03*
X511713D02*
D03*
Y-126131D02*
D03*
Y-123572D02*
D03*
Y-121013D02*
D03*
X519783D02*
D03*
Y-123572D02*
D03*
D79*
X464370Y-130034D02*
D03*
X456890D02*
D03*
Y-121639D02*
D03*
X460630D02*
D03*
D80*
X464370D02*
D03*
D84*
X118504Y-390698D02*
D03*
D85*
X216142Y-404084D02*
D03*
D86*
X335925Y-124803D02*
D03*
X347539D02*
D03*
X359941Y-136221D02*
D03*
X371555D02*
D03*
X653839Y-260236D02*
D03*
X642224D02*
D03*
X359154Y-124803D02*
D03*
X370768D02*
D03*
D87*
X293445Y-245593D02*
D03*
X309193D02*
D03*
X293445Y-243593D02*
D03*
X309193D02*
D03*
X293445Y-241593D02*
D03*
X309193D02*
D03*
X293445Y-239593D02*
D03*
X309193D02*
D03*
X293445Y-237593D02*
D03*
X309193D02*
D03*
X293445Y-235593D02*
D03*
X309193D02*
D03*
X293445Y-233593D02*
D03*
X309193D02*
D03*
X293445Y-231593D02*
D03*
X309193D02*
D03*
X293445Y-229593D02*
D03*
X309193D02*
D03*
Y-227593D02*
D03*
X293445D02*
D03*
Y-245593D02*
D03*
X309193D02*
D03*
X293445Y-243593D02*
D03*
X309193D02*
D03*
X293445Y-241593D02*
D03*
X309193D02*
D03*
X293445Y-239593D02*
D03*
X309193D02*
D03*
X293445Y-237593D02*
D03*
X309193D02*
D03*
X293445Y-235593D02*
D03*
X309193D02*
D03*
X293445Y-233593D02*
D03*
X309193D02*
D03*
X293445Y-231593D02*
D03*
X309193D02*
D03*
X293445Y-229593D02*
D03*
X309193D02*
D03*
Y-227593D02*
D03*
X293445D02*
D03*
D88*
X639764Y-236221D02*
D03*
Y-241732D02*
D03*
X554419Y-216650D02*
D03*
Y-222161D02*
D03*
X602919Y-243661D02*
D03*
Y-238150D02*
D03*
X586419Y-243661D02*
D03*
Y-238150D02*
D03*
X596919Y-243661D02*
D03*
Y-238150D02*
D03*
X591919Y-243661D02*
D03*
Y-238150D02*
D03*
X82677Y-123228D02*
D03*
Y-128740D02*
D03*
X75845Y-116496D02*
D03*
Y-110984D02*
D03*
X500000Y-137647D02*
D03*
Y-132135D02*
D03*
X67913Y-335433D02*
D03*
Y-329921D02*
D03*
X601723Y-136417D02*
D03*
Y-141929D02*
D03*
X581250Y-136417D02*
D03*
Y-141929D02*
D03*
X588337Y-136417D02*
D03*
Y-141929D02*
D03*
X595030Y-136417D02*
D03*
Y-141929D02*
D03*
X544813Y-120161D02*
D03*
Y-114650D02*
D03*
X114173Y-73868D02*
D03*
Y-79379D02*
D03*
X98425Y-92568D02*
D03*
Y-98080D02*
D03*
X348106Y-104238D02*
D03*
Y-98726D02*
D03*
X447835Y-128592D02*
D03*
Y-123080D02*
D03*
X244094Y-115206D02*
D03*
Y-120718D02*
D03*
X67913Y-169488D02*
D03*
Y-175000D02*
D03*
X68898Y-275787D02*
D03*
Y-281299D02*
D03*
X68898Y-221654D02*
D03*
Y-227165D02*
D03*
X528543Y-112057D02*
D03*
Y-117569D02*
D03*
D89*
X600984Y-173622D02*
D03*
X562795D02*
D03*
X579824Y-274905D02*
D03*
X618013D02*
D03*
D90*
X560919Y-243150D02*
D03*
X565919D02*
D03*
X570919D02*
D03*
X575919D02*
D03*
Y-223661D02*
D03*
X570919D02*
D03*
X565919D02*
D03*
X560919D02*
D03*
X551813Y-120661D02*
D03*
X556813D02*
D03*
X561813D02*
D03*
X566813D02*
D03*
Y-140150D02*
D03*
X561813D02*
D03*
X556813D02*
D03*
X551813D02*
D03*
D91*
X549702Y-231906D02*
D03*
X555135D02*
D03*
X570757Y-206890D02*
D03*
X576191D02*
D03*
X571097Y-117206D02*
D03*
X576530D02*
D03*
X654291Y-249606D02*
D03*
X648858D02*
D03*
X618298Y-118307D02*
D03*
X623731D02*
D03*
X540597Y-128405D02*
D03*
X546030D02*
D03*
X561211Y-105315D02*
D03*
X566644D02*
D03*
X110709Y-263632D02*
D03*
X116142D02*
D03*
D92*
X547376Y-240905D02*
D03*
X554462D02*
D03*
X545857Y-138406D02*
D03*
X538770D02*
D03*
X619439Y-132480D02*
D03*
X626526D02*
D03*
X619439Y-141142D02*
D03*
X626526D02*
D03*
D93*
X610919Y-243949D02*
D03*
Y-236862D02*
D03*
X621919Y-243949D02*
D03*
Y-236862D02*
D03*
X648425Y-234252D02*
D03*
Y-241339D02*
D03*
X357480Y-96850D02*
D03*
Y-103937D02*
D03*
D94*
X582135Y-227795D02*
D03*
Y-233228D02*
D03*
X582419Y-217189D02*
D03*
Y-222622D02*
D03*
X573770Y-136063D02*
D03*
Y-141496D02*
D03*
D95*
X570761Y-212906D02*
D03*
X576076D02*
D03*
X566471Y-111406D02*
D03*
X561156D02*
D03*
D96*
X568569Y-254906D02*
D03*
X562269D02*
D03*
D97*
X386914Y-160521D02*
D03*
X474906D02*
D03*
Y-308553D02*
D03*
X386914D02*
D03*
D98*
X424024Y-168449D02*
D03*
X422056D02*
D03*
X447647D02*
D03*
X463394D02*
D03*
X451584D02*
D03*
X443710D02*
D03*
X455521D02*
D03*
X433868D02*
D03*
X437805D02*
D03*
X453552Y-152505D02*
D03*
X445679D02*
D03*
X451584D02*
D03*
X463394D02*
D03*
X461427Y-168449D02*
D03*
X457489D02*
D03*
X406309D02*
D03*
X427961D02*
D03*
X447647Y-152505D02*
D03*
X457489D02*
D03*
X453552Y-168449D02*
D03*
X445679D02*
D03*
X441742D02*
D03*
X425993D02*
D03*
X461427Y-152505D02*
D03*
X435836Y-168449D02*
D03*
X431898D02*
D03*
X455521Y-152505D02*
D03*
X416151Y-168449D02*
D03*
X418119D02*
D03*
X412214Y-152505D02*
D03*
X406309D02*
D03*
X441742D02*
D03*
X443710D02*
D03*
X404340Y-168449D02*
D03*
X396465Y-152505D02*
D03*
X394498Y-168449D02*
D03*
X418119Y-152505D02*
D03*
X404340D02*
D03*
X414183D02*
D03*
X416151D02*
D03*
X422056D02*
D03*
X433868D02*
D03*
X427961D02*
D03*
X398434D02*
D03*
X408277D02*
D03*
X402372D02*
D03*
X435836D02*
D03*
X396465Y-168449D02*
D03*
X394498Y-152505D02*
D03*
X424024D02*
D03*
X437805D02*
D03*
X398434Y-168449D02*
D03*
X392529D02*
D03*
X402372D02*
D03*
X392529Y-152505D02*
D03*
X408277Y-168449D02*
D03*
X431898Y-152505D02*
D03*
X425993D02*
D03*
X412214Y-168449D02*
D03*
X465364Y-152505D02*
D03*
Y-168449D02*
D03*
X400403D02*
D03*
X410246D02*
D03*
X420088D02*
D03*
X429931D02*
D03*
X439773D02*
D03*
X449615D02*
D03*
X459457D02*
D03*
X400403Y-152505D02*
D03*
X410246D02*
D03*
X420088D02*
D03*
X429931D02*
D03*
X439773D02*
D03*
X449615D02*
D03*
X459457D02*
D03*
X469301D02*
D03*
Y-168449D02*
D03*
X467332D02*
D03*
X414183D02*
D03*
X467332Y-152505D02*
D03*
X437795Y-300625D02*
D03*
X439763D02*
D03*
X414173D02*
D03*
X398425D02*
D03*
X410236D02*
D03*
X418110D02*
D03*
X406299D02*
D03*
X427952D02*
D03*
X424015D02*
D03*
X408267Y-316569D02*
D03*
X416141D02*
D03*
X410236D02*
D03*
X398425D02*
D03*
X400393Y-300625D02*
D03*
X404330D02*
D03*
X455511D02*
D03*
X433858D02*
D03*
X414173Y-316569D02*
D03*
X404330D02*
D03*
X408267Y-300625D02*
D03*
X416141D02*
D03*
X420078D02*
D03*
X435826D02*
D03*
X400393Y-316569D02*
D03*
X425984Y-300625D02*
D03*
X429921D02*
D03*
X406299Y-316569D02*
D03*
X445669Y-300625D02*
D03*
X443700D02*
D03*
X449606Y-316569D02*
D03*
X455511D02*
D03*
X420078D02*
D03*
X418110D02*
D03*
X457480Y-300625D02*
D03*
X465354Y-316569D02*
D03*
X467322Y-300625D02*
D03*
X443700Y-316569D02*
D03*
X457480D02*
D03*
X447637D02*
D03*
X445669D02*
D03*
X439763D02*
D03*
X427952D02*
D03*
X433858D02*
D03*
X463385D02*
D03*
X453543D02*
D03*
X459448D02*
D03*
X425984D02*
D03*
X465354Y-300625D02*
D03*
X467322Y-316569D02*
D03*
X437795D02*
D03*
X424015D02*
D03*
X463385Y-300625D02*
D03*
X469291D02*
D03*
X459448D02*
D03*
X469291Y-316569D02*
D03*
X453543Y-300625D02*
D03*
X429921Y-316569D02*
D03*
X435826D02*
D03*
X449606Y-300625D02*
D03*
X396456Y-316569D02*
D03*
Y-300625D02*
D03*
X461417D02*
D03*
X451574D02*
D03*
X441732D02*
D03*
X431889D02*
D03*
X422047D02*
D03*
X412204D02*
D03*
X402362D02*
D03*
X461417Y-316569D02*
D03*
X451574D02*
D03*
X441732D02*
D03*
X431889D02*
D03*
X422047D02*
D03*
X412204D02*
D03*
X402362D02*
D03*
X392519D02*
D03*
Y-300625D02*
D03*
X394488D02*
D03*
X447637D02*
D03*
X394488Y-316569D02*
D03*
D99*
X528351Y-190049D02*
D03*
Y-278041D02*
D03*
X340949D02*
D03*
Y-190049D02*
D03*
D100*
X520423Y-227160D02*
D03*
Y-225192D02*
D03*
Y-250782D02*
D03*
Y-266530D02*
D03*
Y-254719D02*
D03*
Y-246845D02*
D03*
Y-258656D02*
D03*
Y-237003D02*
D03*
Y-240940D02*
D03*
X536367Y-256688D02*
D03*
Y-248814D02*
D03*
Y-254719D02*
D03*
Y-266530D02*
D03*
X520423Y-264562D02*
D03*
Y-260625D02*
D03*
Y-209444D02*
D03*
Y-231097D02*
D03*
X536367Y-250782D02*
D03*
Y-260625D02*
D03*
X520423Y-256688D02*
D03*
Y-248814D02*
D03*
Y-244877D02*
D03*
Y-229129D02*
D03*
X536367Y-264562D02*
D03*
X520423Y-238971D02*
D03*
Y-235034D02*
D03*
X536367Y-258656D02*
D03*
X520423Y-219286D02*
D03*
Y-221255D02*
D03*
X536367Y-215349D02*
D03*
Y-209444D02*
D03*
Y-244877D02*
D03*
Y-246845D02*
D03*
X520423Y-207475D02*
D03*
X536367Y-199601D02*
D03*
X520423Y-197633D02*
D03*
X536367Y-221255D02*
D03*
Y-207475D02*
D03*
Y-217318D02*
D03*
Y-219286D02*
D03*
Y-225192D02*
D03*
Y-237003D02*
D03*
Y-231097D02*
D03*
Y-201570D02*
D03*
Y-211412D02*
D03*
Y-205507D02*
D03*
Y-238971D02*
D03*
X520423Y-199601D02*
D03*
X536367Y-197633D02*
D03*
Y-227160D02*
D03*
Y-240940D02*
D03*
X520423Y-201570D02*
D03*
Y-195664D02*
D03*
Y-205507D02*
D03*
X536367Y-195664D02*
D03*
X520423Y-211412D02*
D03*
X536367Y-235034D02*
D03*
Y-229129D02*
D03*
X520423Y-215349D02*
D03*
X536367Y-268499D02*
D03*
X520423D02*
D03*
Y-203538D02*
D03*
Y-213381D02*
D03*
Y-223223D02*
D03*
Y-233066D02*
D03*
Y-242908D02*
D03*
Y-252751D02*
D03*
Y-262593D02*
D03*
X536367Y-203538D02*
D03*
Y-213381D02*
D03*
Y-223223D02*
D03*
Y-233066D02*
D03*
Y-242908D02*
D03*
Y-252751D02*
D03*
Y-262593D02*
D03*
Y-272436D02*
D03*
X520423D02*
D03*
Y-270467D02*
D03*
Y-217318D02*
D03*
X536367Y-270467D02*
D03*
X348876Y-240930D02*
D03*
Y-242898D02*
D03*
Y-217308D02*
D03*
Y-201560D02*
D03*
Y-213371D02*
D03*
Y-221245D02*
D03*
Y-209434D02*
D03*
Y-231087D02*
D03*
Y-227150D02*
D03*
X332932Y-211402D02*
D03*
Y-219276D02*
D03*
Y-213371D02*
D03*
Y-201560D02*
D03*
X348876Y-203528D02*
D03*
Y-207465D02*
D03*
Y-258646D02*
D03*
Y-236993D02*
D03*
X332932Y-217308D02*
D03*
Y-207465D02*
D03*
X348876Y-211402D02*
D03*
Y-219276D02*
D03*
Y-223213D02*
D03*
Y-238961D02*
D03*
X332932Y-203528D02*
D03*
X348876Y-229119D02*
D03*
Y-233056D02*
D03*
X332932Y-209434D02*
D03*
X348876Y-248804D02*
D03*
Y-246835D02*
D03*
X332932Y-252741D02*
D03*
Y-258646D02*
D03*
Y-223213D02*
D03*
Y-221245D02*
D03*
X348876Y-260615D02*
D03*
X332932Y-268489D02*
D03*
X348876Y-270457D02*
D03*
X332932Y-246835D02*
D03*
Y-260615D02*
D03*
Y-250772D02*
D03*
Y-248804D02*
D03*
Y-242898D02*
D03*
Y-231087D02*
D03*
Y-236993D02*
D03*
Y-266520D02*
D03*
Y-256678D02*
D03*
Y-262583D02*
D03*
Y-229119D02*
D03*
X348876Y-268489D02*
D03*
X332932Y-270457D02*
D03*
Y-240930D02*
D03*
Y-227150D02*
D03*
X348876Y-266520D02*
D03*
Y-272426D02*
D03*
Y-262583D02*
D03*
X332932Y-272426D02*
D03*
X348876Y-256678D02*
D03*
X332932Y-233056D02*
D03*
Y-238961D02*
D03*
X348876Y-252741D02*
D03*
X332932Y-199591D02*
D03*
X348876D02*
D03*
Y-264552D02*
D03*
Y-254709D02*
D03*
Y-244867D02*
D03*
Y-235024D02*
D03*
Y-225182D02*
D03*
Y-215339D02*
D03*
Y-205497D02*
D03*
X332932Y-264552D02*
D03*
Y-254709D02*
D03*
Y-244867D02*
D03*
Y-235024D02*
D03*
Y-225182D02*
D03*
Y-215339D02*
D03*
Y-205497D02*
D03*
Y-195654D02*
D03*
X348876D02*
D03*
Y-197623D02*
D03*
Y-250772D02*
D03*
X332932Y-197623D02*
D03*
D101*
X630240Y-37647D02*
D03*
X649390D02*
D03*
Y-29773D02*
D03*
X630240D02*
D03*
Y-21899D02*
D03*
X649390D02*
D03*
X630240Y-14025D02*
D03*
X649390D02*
D03*
X74036Y-73671D02*
D03*
X93186D02*
D03*
X74036Y-65797D02*
D03*
X93186D02*
D03*
Y-57923D02*
D03*
X74036D02*
D03*
Y-50049D02*
D03*
X93186D02*
D03*
D102*
X609291Y-316535D02*
D03*
Y-343543D02*
D03*
X599291Y-316535D02*
D03*
Y-343543D02*
D03*
X589291Y-316535D02*
D03*
Y-343543D02*
D03*
X579291Y-316535D02*
D03*
Y-343543D02*
D03*
X569291Y-316535D02*
D03*
Y-343543D02*
D03*
D103*
X262806Y-132277D02*
D03*
X257294D02*
D03*
X248031Y-127165D02*
D03*
X242520D02*
D03*
X59646Y-316929D02*
D03*
X54134D02*
D03*
X60827Y-210630D02*
D03*
X55315D02*
D03*
X60827Y-262795D02*
D03*
X55315D02*
D03*
X54331Y-157480D02*
D03*
X59842D02*
D03*
D104*
X540493Y-331738D02*
D03*
X532619D02*
D03*
X540099Y-347880D02*
D03*
X532225D02*
D03*
D105*
X655118Y-346457D02*
D03*
Y-338583D02*
D03*
X637008Y-346850D02*
D03*
Y-338976D02*
D03*
D106*
X515198Y-329179D02*
D03*
Y-334297D02*
D03*
X524056Y-331738D02*
D03*
X515099Y-345321D02*
D03*
Y-350439D02*
D03*
X523958Y-347880D02*
D03*
D107*
X639567Y-320374D02*
D03*
X634449D02*
D03*
X637008Y-329232D02*
D03*
X658268Y-320473D02*
D03*
X653150D02*
D03*
X655709Y-329331D02*
D03*
D108*
X81988Y-215551D02*
D03*
Y-213583D02*
D03*
Y-211614D02*
D03*
Y-209646D02*
D03*
X69587D02*
D03*
Y-211614D02*
D03*
Y-213583D02*
D03*
Y-215551D02*
D03*
X81004Y-162402D02*
D03*
Y-160433D02*
D03*
Y-158465D02*
D03*
Y-156496D02*
D03*
X68602D02*
D03*
Y-158465D02*
D03*
Y-160433D02*
D03*
Y-162402D02*
D03*
X81988Y-267717D02*
D03*
Y-265748D02*
D03*
Y-263779D02*
D03*
Y-261811D02*
D03*
X69587D02*
D03*
Y-263779D02*
D03*
Y-265748D02*
D03*
Y-267717D02*
D03*
X81004Y-321850D02*
D03*
Y-319882D02*
D03*
Y-317913D02*
D03*
Y-315945D02*
D03*
X68602D02*
D03*
Y-317913D02*
D03*
Y-319882D02*
D03*
Y-321850D02*
D03*
D109*
X649390Y-14025D02*
D03*
Y-29773D02*
D03*
Y-21899D02*
D03*
Y-37647D02*
D03*
X631890Y-14025D02*
D03*
Y-21899D02*
D03*
Y-29773D02*
D03*
Y-37647D02*
D03*
X74036Y-73671D02*
D03*
Y-57923D02*
D03*
Y-65797D02*
D03*
Y-50049D02*
D03*
X91536Y-73671D02*
D03*
Y-65797D02*
D03*
Y-57923D02*
D03*
Y-50049D02*
D03*
D110*
X47244Y-4626D02*
D03*
Y689D02*
D03*
X40354Y-4626D02*
D03*
Y689D02*
D03*
X33465Y-4626D02*
D03*
Y689D02*
D03*
X26575Y-4626D02*
D03*
Y689D02*
D03*
X199803Y-119439D02*
D03*
Y-114517D02*
D03*
D111*
X94193Y-120079D02*
D03*
Y-122047D02*
D03*
Y-124016D02*
D03*
Y-125984D02*
D03*
Y-127953D02*
D03*
Y-129921D02*
D03*
Y-131890D02*
D03*
X112500D02*
D03*
Y-129921D02*
D03*
Y-127953D02*
D03*
Y-125984D02*
D03*
Y-124016D02*
D03*
Y-122047D02*
D03*
Y-120079D02*
D03*
D112*
X97441Y-135138D02*
D03*
X99410D02*
D03*
X101378D02*
D03*
X103347D02*
D03*
X105315D02*
D03*
X107283D02*
D03*
X109252D02*
D03*
X109252Y-116831D02*
D03*
X107283D02*
D03*
X105315D02*
D03*
X103347D02*
D03*
X101378D02*
D03*
X99410D02*
D03*
X97441D02*
D03*
D113*
X103347Y-125984D02*
D03*
D114*
X-18406Y-187795D02*
D03*
Y-176772D02*
D03*
Y-240551D02*
D03*
Y-229528D02*
D03*
Y-294094D02*
D03*
Y-283071D02*
D03*
Y-346850D02*
D03*
Y-335827D02*
D03*
Y-113976D02*
D03*
Y-102953D02*
D03*
Y-70669D02*
D03*
Y-59646D02*
D03*
D115*
X-19685Y-184055D02*
D03*
Y-180512D02*
D03*
Y-236811D02*
D03*
Y-233268D02*
D03*
Y-290354D02*
D03*
Y-286811D02*
D03*
Y-343110D02*
D03*
Y-339567D02*
D03*
Y-110236D02*
D03*
Y-106693D02*
D03*
Y-66929D02*
D03*
Y-63386D02*
D03*
D116*
X82677Y-135827D02*
D03*
X76772D02*
D03*
D117*
X44291Y-256988D02*
D03*
Y-268602D02*
D03*
Y-151673D02*
D03*
Y-163287D02*
D03*
Y-311122D02*
D03*
Y-322736D02*
D03*
Y-204823D02*
D03*
Y-216437D02*
D03*
D118*
X38287Y-262795D02*
D03*
Y-157480D02*
D03*
Y-316929D02*
D03*
Y-210630D02*
D03*
D119*
X74803Y-335630D02*
D03*
Y-329724D02*
D03*
X82677Y-335630D02*
D03*
Y-329724D02*
D03*
X75787Y-227362D02*
D03*
Y-221457D02*
D03*
X82677Y-227362D02*
D03*
Y-221457D02*
D03*
X83661Y-281496D02*
D03*
Y-275590D02*
D03*
X75787Y-281496D02*
D03*
Y-275590D02*
D03*
X74803Y-175197D02*
D03*
Y-169291D02*
D03*
X82677Y-175197D02*
D03*
Y-169291D02*
D03*
X399606Y-134695D02*
D03*
Y-128789D02*
D03*
X405512Y-134695D02*
D03*
Y-128789D02*
D03*
D120*
X487205Y-137647D02*
D03*
X481693D02*
D03*
X650197Y-50049D02*
D03*
X644685D02*
D03*
X615522Y-14017D02*
D03*
X610010D02*
D03*
X263976Y-112057D02*
D03*
X269488D02*
D03*
X518701D02*
D03*
X513189D02*
D03*
D121*
X460925Y-137647D02*
D03*
X456398D02*
D03*
D122*
X31496Y-184055D02*
D03*
Y-291732D02*
D03*
D123*
X38189Y-184055D02*
D03*
Y-175394D02*
D03*
X30709D02*
D03*
X38189Y-291732D02*
D03*
Y-283071D02*
D03*
X30709D02*
D03*
D124*
X267323Y-126821D02*
D03*
X262205D02*
D03*
X267323Y-118947D02*
D03*
X262205D02*
D03*
D125*
X276969Y-357824D02*
D03*
Y-354478D02*
D03*
X221850Y-357824D02*
D03*
Y-354478D02*
D03*
D126*
X281102Y-401427D02*
D03*
X159055D02*
D03*
X155118D02*
D03*
X151181D02*
D03*
X178740D02*
D03*
X222047D02*
D03*
X265354D02*
D03*
X261417D02*
D03*
X249606D02*
D03*
X245669D02*
D03*
X233858D02*
D03*
X229921D02*
D03*
X214173D02*
D03*
X210236D02*
D03*
X186614D02*
D03*
X182677D02*
D03*
X202362D02*
D03*
X273228D02*
D03*
X166929D02*
D03*
X170866D02*
D03*
X190551D02*
D03*
X269291D02*
D03*
X257480D02*
D03*
X241732D02*
D03*
X237795D02*
D03*
X174803D02*
D03*
X162992D02*
D03*
X253543D02*
D03*
X206299D02*
D03*
X218110D02*
D03*
X225984D02*
D03*
D127*
X277165Y-399477D02*
D03*
D128*
X279528Y-113946D02*
D03*
Y-118947D02*
D03*
Y-123946D02*
D03*
Y-128946D02*
D03*
X298425Y-113946D02*
D03*
Y-118947D02*
D03*
Y-123946D02*
D03*
Y-128946D02*
D03*
D129*
X209252Y-114399D02*
D03*
Y-119399D02*
D03*
Y-124399D02*
D03*
Y-129399D02*
D03*
X227756Y-114399D02*
D03*
Y-119399D02*
D03*
Y-124399D02*
D03*
Y-129399D02*
D03*
D130*
X548425Y-157087D02*
D03*
Y-150787D02*
D03*
D131*
X618012Y-124409D02*
D03*
X623721D02*
D03*
D132*
X237205Y-125639D02*
D03*
Y-120127D02*
D03*
D133*
X142362Y-120079D02*
D03*
X152362D02*
D03*
X162362D02*
D03*
X579055Y13937D02*
D03*
X569055D02*
D03*
X559055D02*
D03*
X549055D02*
D03*
X539055D02*
D03*
X589055Y3937D02*
D03*
X579055D02*
D03*
X569055D02*
D03*
X559055D02*
D03*
X549055D02*
D03*
X539055D02*
D03*
D134*
X172362Y-120079D02*
D03*
X589055Y13937D02*
D03*
D135*
X258472Y-327165D02*
D03*
X282283D02*
D03*
X294094D02*
D03*
X302362Y-156693D02*
D03*
Y-316535D02*
D03*
X142520D02*
D03*
Y-236614D02*
D03*
Y-156693D02*
D03*
X270472Y-327165D02*
D03*
X246472D02*
D03*
D136*
X674409Y-194488D02*
D03*
Y-161417D02*
D03*
X348211Y-89891D02*
D03*
X357798Y-89963D02*
D03*
D137*
X645669Y-194488D02*
D03*
X624016D02*
D03*
Y-177953D02*
D03*
X645669D02*
D03*
X624016Y-161417D02*
D03*
X645669D02*
D03*
D138*
X391545Y-160477D02*
D03*
X470285D02*
D03*
X528395Y-194680D02*
D03*
Y-273420D02*
D03*
X470275Y-308597D02*
D03*
X391535D02*
D03*
X340904Y-273410D02*
D03*
Y-194670D02*
D03*
D139*
X533015Y-312764D02*
D03*
X336415Y-155764D02*
D03*
X336515Y-312764D02*
D03*
X533015Y-155764D02*
D03*
D140*
X604291Y-330039D02*
D03*
X574291D02*
D03*
D141*
X-18464Y-326781D02*
D03*
X1535D02*
D03*
Y-306781D02*
D03*
X-18464D02*
D03*
X-18465Y-273630D02*
D03*
X1535D02*
D03*
Y-253630D02*
D03*
X-18465D02*
D03*
Y-220480D02*
D03*
X1535D02*
D03*
Y-200480D02*
D03*
X-18465D02*
D03*
X-18464Y-167332D02*
D03*
X1535D02*
D03*
Y-147332D02*
D03*
X-18464D02*
D03*
D142*
X-8465Y-316781D02*
D03*
X-8465Y-263630D02*
D03*
Y-210480D02*
D03*
X-8465Y-157332D02*
D03*
D143*
X640640Y-33710D02*
D03*
Y-17962D02*
D03*
X82785Y-53986D02*
D03*
Y-69734D02*
D03*
D144*
X0Y0D02*
D03*
X0Y-378395D02*
D03*
X685039Y0D02*
D03*
X685039Y-340551D02*
D03*
X486221Y-340551D02*
D03*
D145*
X416835Y-196581D02*
D03*
X411811Y-196850D02*
D03*
X314658Y-244775D02*
D03*
X315097Y-235081D02*
D03*
X315226Y-230634D02*
D03*
X314864Y-227997D02*
D03*
X314503Y-225180D02*
D03*
D146*
X564896Y-236697D02*
D03*
D147*
X651545Y-95108D02*
D03*
X413356Y7254D02*
D03*
Y-95108D02*
D03*
X651545Y7254D02*
D03*
X71880Y7412D02*
D03*
X310069Y-94950D02*
D03*
Y7412D02*
D03*
X71880Y-94950D02*
D03*
D148*
X99016Y-121653D02*
D03*
X103347D02*
D03*
X107677D02*
D03*
X99016Y-125984D02*
D03*
X103347D02*
D03*
X107677D02*
D03*
X99016Y-130315D02*
D03*
X103347D02*
D03*
X107677D02*
D03*
M02*
